(kicad_pcb
	(version 20260206)
	(generator "pcbnew")
	(generator_version "10.0")
	(general
		(thickness 1.6)
		(legacy_teardrops no)
	)
	(paper "A4")
	(title_block
		(title "03242023_DA0F0TMBIJ0_F0T_Motherboard_J_brd_V01_OCP.brd")
		(comment 1 "Grand Teton / footprints 2248-2254 of 6105")
	)
	(layers
		(0 "F.Cu" signal "TOP")
		(4 "In1.Cu" signal "GND")
		(6 "In2.Cu" signal "IN1")
		(8 "In3.Cu" signal "GND1")
		(10 "In4.Cu" signal "IN2")
		(12 "In5.Cu" signal "GND2")
		(14 "In6.Cu" signal "IN3")
		(16 "In7.Cu" signal "GND3")
		(18 "In8.Cu" signal "VCC")
		(20 "In9.Cu" signal "VCC1")
		(22 "In10.Cu" signal "GND4")
		(24 "In11.Cu" signal "IN4")
		(26 "In12.Cu" signal "GND5")
		(28 "In13.Cu" signal "IN5")
		(30 "In14.Cu" signal "GND6")
		(32 "In15.Cu" signal "IN6")
		(34 "In16.Cu" signal "GND7")
		(2 "B.Cu" signal "BOTTOM")
		(9 "F.Adhes" user "F.Adhesive")
		(11 "B.Adhes" user "B.Adhesive")
		(13 "F.Paste" user "Package Geometry/Pastemask Top")
		(15 "B.Paste" user "Package Geometry/Pastemask Bottom")
		(5 "F.SilkS" user "Ref Des/Silkscreen Top")
		(7 "B.SilkS" user "Ref Des/Silkscreen Bottom")
		(1 "F.Mask" user "Board Geometry/Soldermask Top")
		(3 "B.Mask" user "Board Geometry/Soldermask Bottom")
		(17 "Dwgs.User" user "User.Drawings")
		(19 "Cmts.User" user "User.Comments")
		(21 "Eco1.User" user "User.Eco1")
		(23 "Eco2.User" user "User.Eco2")
		(25 "Edge.Cuts" user "Board Geometry/Outline")
		(27 "Margin" user)
		(31 "F.CrtYd" user "Package Geometry/Place Bound Top")
		(29 "B.CrtYd" user "Package Geometry/Place Bound Bottom")
		(35 "F.Fab" user "Ref Des/Assembly Top")
		(33 "B.Fab" user "Ref Des/Assembly Bottom")
	)
	(footprint ""
		(layer "F.Cu")
		(at 80.913478 -23.317962)
		(property "Reference" "PC2150"
			(at 0 0 0)
			(layer "F.SilkS")
			(hide yes)
			(effects
				(font
					(size 1.27 1.27)
				)
			)
		)
		(property "Value" ""
			(at 0 0 0)
			(layer "F.Fab")
			(effects
				(font
					(size 1.27 1.27)
				)
			)
		)
		(duplicate_pad_numbers_are_jumpers no)
		(fp_line
			(start -0.7874 -0.4064)
			(end 0.7874 -0.4064)
			(stroke
				(width 0.1524)
				(type default)
			)
			(layer "F.SilkS")
		)
		(fp_line
			(start -0.7874 0.4064)
			(end -0.7874 -0.4064)
			(stroke
				(width 0.1524)
				(type default)
			)
			(layer "F.SilkS")
		)
		(fp_line
			(start 0.7874 -0.4064)
			(end 0.7874 0.4064)
			(stroke
				(width 0.1524)
				(type default)
			)
			(layer "F.SilkS")
		)
		(fp_line
			(start 0.7874 0.4064)
			(end -0.7874 0.4064)
			(stroke
				(width 0.1524)
				(type default)
			)
			(layer "F.SilkS")
		)
		(fp_line
			(start -0.67945 -0.305054)
			(end -0.12065 -0.305054)
			(stroke
				(width 0.1)
				(type default)
			)
			(layer "F.Fab")
		)
		(fp_line
			(start -0.67945 0.3048)
			(end -0.67945 -0.305054)
			(stroke
				(width 0.1)
				(type default)
			)
			(layer "F.Fab")
		)
		(fp_line
			(start -0.12065 -0.305054)
			(end -0.12065 -0.2794)
			(stroke
				(width 0.1)
				(type default)
			)
			(layer "F.Fab")
		)
		(fp_line
			(start -0.12065 -0.2794)
			(end 0.12065 -0.2794)
			(stroke
				(width 0.1)
				(type default)
			)
			(layer "F.Fab")
		)
		(fp_line
			(start -0.12065 0.2794)
			(end -0.12065 0.3048)
			(stroke
				(width 0.1)
				(type default)
			)
			(layer "F.Fab")
		)
		(fp_line
			(start -0.12065 0.3048)
			(end -0.67945 0.3048)
			(stroke
				(width 0.1)
				(type default)
			)
			(layer "F.Fab")
		)
		(fp_line
			(start 0.120396 0.2794)
			(end -0.12065 0.2794)
			(stroke
				(width 0.1)
				(type default)
			)
			(layer "F.Fab")
		)
		(fp_line
			(start 0.120396 0.3048)
			(end 0.120396 0.2794)
			(stroke
				(width 0.1)
				(type default)
			)
			(layer "F.Fab")
		)
		(fp_line
			(start 0.12065 -0.3048)
			(end 0.67945 -0.3048)
			(stroke
				(width 0.1)
				(type default)
			)
			(layer "F.Fab")
		)
		(fp_line
			(start 0.12065 -0.2794)
			(end 0.12065 -0.3048)
			(stroke
				(width 0.1)
				(type default)
			)
			(layer "F.Fab")
		)
		(fp_line
			(start 0.67945 -0.3048)
			(end 0.67945 0.3048)
			(stroke
				(width 0.1)
				(type default)
			)
			(layer "F.Fab")
		)
		(fp_line
			(start 0.67945 0.3048)
			(end 0.120396 0.3048)
			(stroke
				(width 0.1)
				(type default)
			)
			(layer "F.Fab")
		)
		(pad "1" smd circle
			(at -0.40005 0)
			(size 0 0)
			(layers "F.Cu" "F.Mask" "F.Paste")
			(net "P12V_OCP_GATE_2")
		)
		(pad "2" smd circle
			(at 0.40005 0)
			(size 0 0)
			(layers "F.Cu" "F.Mask" "F.Paste")
			(net "GND")
		)
	)
	(footprint ""
		(layer "F.Cu")
		(at 433.076858 -166.405814)
		(property "Reference" "PC1655"
			(at 0 0 0)
			(layer "F.SilkS")
			(hide yes)
			(effects
				(font
					(size 1.27 1.27)
				)
			)
		)
		(property "Value" ""
			(at 0 0 0)
			(layer "F.Fab")
			(effects
				(font
					(size 1.27 1.27)
				)
			)
		)
		(duplicate_pad_numbers_are_jumpers no)
		(fp_line
			(start -0.7874 -0.4064)
			(end 0.7874 -0.4064)
			(stroke
				(width 0.1524)
				(type default)
			)
			(layer "F.SilkS")
		)
		(fp_line
			(start -0.7874 0.4064)
			(end -0.7874 -0.4064)
			(stroke
				(width 0.1524)
				(type default)
			)
			(layer "F.SilkS")
		)
		(fp_line
			(start 0.7874 -0.4064)
			(end 0.7874 0.4064)
			(stroke
				(width 0.1524)
				(type default)
			)
			(layer "F.SilkS")
		)
		(fp_line
			(start 0.7874 0.4064)
			(end -0.7874 0.4064)
			(stroke
				(width 0.1524)
				(type default)
			)
			(layer "F.SilkS")
		)
		(fp_line
			(start -0.67945 -0.305054)
			(end -0.12065 -0.305054)
			(stroke
				(width 0.1)
				(type default)
			)
			(layer "F.Fab")
		)
		(fp_line
			(start -0.67945 0.3048)
			(end -0.67945 -0.305054)
			(stroke
				(width 0.1)
				(type default)
			)
			(layer "F.Fab")
		)
		(fp_line
			(start -0.12065 -0.305054)
			(end -0.12065 -0.2794)
			(stroke
				(width 0.1)
				(type default)
			)
			(layer "F.Fab")
		)
		(fp_line
			(start -0.12065 -0.2794)
			(end 0.12065 -0.2794)
			(stroke
				(width 0.1)
				(type default)
			)
			(layer "F.Fab")
		)
		(fp_line
			(start -0.12065 0.2794)
			(end -0.12065 0.3048)
			(stroke
				(width 0.1)
				(type default)
			)
			(layer "F.Fab")
		)
		(fp_line
			(start -0.12065 0.3048)
			(end -0.67945 0.3048)
			(stroke
				(width 0.1)
				(type default)
			)
			(layer "F.Fab")
		)
		(fp_line
			(start 0.120396 0.2794)
			(end -0.12065 0.2794)
			(stroke
				(width 0.1)
				(type default)
			)
			(layer "F.Fab")
		)
		(fp_line
			(start 0.120396 0.3048)
			(end 0.120396 0.2794)
			(stroke
				(width 0.1)
				(type default)
			)
			(layer "F.Fab")
		)
		(fp_line
			(start 0.12065 -0.3048)
			(end 0.67945 -0.3048)
			(stroke
				(width 0.1)
				(type default)
			)
			(layer "F.Fab")
		)
		(fp_line
			(start 0.12065 -0.2794)
			(end 0.12065 -0.3048)
			(stroke
				(width 0.1)
				(type default)
			)
			(layer "F.Fab")
		)
		(fp_line
			(start 0.67945 -0.3048)
			(end 0.67945 0.3048)
			(stroke
				(width 0.1)
				(type default)
			)
			(layer "F.Fab")
		)
		(fp_line
			(start 0.67945 0.3048)
			(end 0.120396 0.3048)
			(stroke
				(width 0.1)
				(type default)
			)
			(layer "F.Fab")
		)
		(pad "1" smd circle
			(at -0.40005 0)
			(size 0 0)
			(layers "F.Cu" "F.Mask" "F.Paste")
			(net "P12V_AUX")
		)
		(pad "2" smd circle
			(at 0.40005 0)
			(size 0 0)
			(layers "F.Cu" "F.Mask" "F.Paste")
			(net "GND")
		)
	)
	(footprint ""
		(layer "F.Cu")
		(at 158.138368 -31.341568 90)
		(property "Reference" "R4459"
			(at 0 0 90)
			(layer "F.SilkS")
			(hide yes)
			(effects
				(font
					(size 1.27 1.27)
				)
			)
		)
		(property "Value" ""
			(at 0 0 90)
			(layer "F.Fab")
			(effects
				(font
					(size 1.27 1.27)
				)
			)
		)
		(duplicate_pad_numbers_are_jumpers no)
		(fp_line
			(start 0.7874 -0.4064)
			(end 0.7874 0.4064)
			(stroke
				(width 0.1524)
				(type default)
			)
			(layer "F.SilkS")
		)
		(fp_line
			(start -0.7874 -0.4064)
			(end 0.7874 -0.4064)
			(stroke
				(width 0.1524)
				(type default)
			)
			(layer "F.SilkS")
		)
		(fp_line
			(start 0.7874 0.4064)
			(end -0.7874 0.4064)
			(stroke
				(width 0.1524)
				(type default)
			)
			(layer "F.SilkS")
		)
		(fp_line
			(start -0.7874 0.4064)
			(end -0.7874 -0.4064)
			(stroke
				(width 0.1524)
				(type default)
			)
			(layer "F.SilkS")
		)
		(fp_line
			(start -0.12065 -0.305054)
			(end -0.12065 -0.2794)
			(stroke
				(width 0.1)
				(type default)
			)
			(layer "F.Fab")
		)
		(fp_line
			(start -0.67945 -0.305054)
			(end -0.12065 -0.305054)
			(stroke
				(width 0.1)
				(type default)
			)
			(layer "F.Fab")
		)
		(fp_line
			(start 0.67945 -0.3048)
			(end 0.67945 0.3048)
			(stroke
				(width 0.1)
				(type default)
			)
			(layer "F.Fab")
		)
		(fp_line
			(start 0.12065 -0.3048)
			(end 0.67945 -0.3048)
			(stroke
				(width 0.1)
				(type default)
			)
			(layer "F.Fab")
		)
		(fp_line
			(start 0.12065 -0.2794)
			(end 0.12065 -0.3048)
			(stroke
				(width 0.1)
				(type default)
			)
			(layer "F.Fab")
		)
		(fp_line
			(start -0.12065 -0.2794)
			(end 0.12065 -0.2794)
			(stroke
				(width 0.1)
				(type default)
			)
			(layer "F.Fab")
		)
		(fp_line
			(start 0.120396 0.2794)
			(end -0.12065 0.2794)
			(stroke
				(width 0.1)
				(type default)
			)
			(layer "F.Fab")
		)
		(fp_line
			(start -0.12065 0.2794)
			(end -0.12065 0.3048)
			(stroke
				(width 0.1)
				(type default)
			)
			(layer "F.Fab")
		)
		(fp_line
			(start 0.67945 0.3048)
			(end 0.120396 0.3048)
			(stroke
				(width 0.1)
				(type default)
			)
			(layer "F.Fab")
		)
		(fp_line
			(start 0.120396 0.3048)
			(end 0.120396 0.2794)
			(stroke
				(width 0.1)
				(type default)
			)
			(layer "F.Fab")
		)
		(fp_line
			(start -0.12065 0.3048)
			(end -0.67945 0.3048)
			(stroke
				(width 0.1)
				(type default)
			)
			(layer "F.Fab")
		)
		(fp_line
			(start -0.67945 0.3048)
			(end -0.67945 -0.305054)
			(stroke
				(width 0.1)
				(type default)
			)
			(layer "F.Fab")
		)
		(pad "1" smd circle
			(at -0.40005 0 90)
			(size 0 0)
			(layers "F.Cu" "F.Mask" "F.Paste")
			(net "P3V3_AUX")
		)
		(pad "2" smd circle
			(at 0.40005 0 90)
			(size 0 0)
			(layers "F.Cu" "F.Mask" "F.Paste")
			(net "USB_HUB_2_OVCUR4")
		)
	)
	(footprint ""
		(layer "F.Cu")
		(at 90.09888 -56.352948)
		(property "Reference" "R1370"
			(at 0 0 0)
			(layer "F.SilkS")
			(hide yes)
			(effects
				(font
					(size 1.27 1.27)
				)
			)
		)
		(property "Value" ""
			(at 0 0 0)
			(layer "F.Fab")
			(effects
				(font
					(size 1.27 1.27)
				)
			)
		)
		(duplicate_pad_numbers_are_jumpers no)
		(fp_line
			(start -0.7874 -0.4064)
			(end 0.7874 -0.4064)
			(stroke
				(width 0.1524)
				(type default)
			)
			(layer "F.SilkS")
		)
		(fp_line
			(start -0.7874 0.4064)
			(end -0.7874 -0.4064)
			(stroke
				(width 0.1524)
				(type default)
			)
			(layer "F.SilkS")
		)
		(fp_line
			(start 0.7874 -0.4064)
			(end 0.7874 0.4064)
			(stroke
				(width 0.1524)
				(type default)
			)
			(layer "F.SilkS")
		)
		(fp_line
			(start 0.7874 0.4064)
			(end -0.7874 0.4064)
			(stroke
				(width 0.1524)
				(type default)
			)
			(layer "F.SilkS")
		)
		(fp_line
			(start -0.67945 -0.305054)
			(end -0.12065 -0.305054)
			(stroke
				(width 0.1)
				(type default)
			)
			(layer "F.Fab")
		)
		(fp_line
			(start -0.67945 0.3048)
			(end -0.67945 -0.305054)
			(stroke
				(width 0.1)
				(type default)
			)
			(layer "F.Fab")
		)
		(fp_line
			(start -0.12065 -0.305054)
			(end -0.12065 -0.2794)
			(stroke
				(width 0.1)
				(type default)
			)
			(layer "F.Fab")
		)
		(fp_line
			(start -0.12065 -0.2794)
			(end 0.12065 -0.2794)
			(stroke
				(width 0.1)
				(type default)
			)
			(layer "F.Fab")
		)
		(fp_line
			(start -0.12065 0.2794)
			(end -0.12065 0.3048)
			(stroke
				(width 0.1)
				(type default)
			)
			(layer "F.Fab")
		)
		(fp_line
			(start -0.12065 0.3048)
			(end -0.67945 0.3048)
			(stroke
				(width 0.1)
				(type default)
			)
			(layer "F.Fab")
		)
		(fp_line
			(start 0.120396 0.2794)
			(end -0.12065 0.2794)
			(stroke
				(width 0.1)
				(type default)
			)
			(layer "F.Fab")
		)
		(fp_line
			(start 0.120396 0.3048)
			(end 0.120396 0.2794)
			(stroke
				(width 0.1)
				(type default)
			)
			(layer "F.Fab")
		)
		(fp_line
			(start 0.12065 -0.3048)
			(end 0.67945 -0.3048)
			(stroke
				(width 0.1)
				(type default)
			)
			(layer "F.Fab")
		)
		(fp_line
			(start 0.12065 -0.2794)
			(end 0.12065 -0.3048)
			(stroke
				(width 0.1)
				(type default)
			)
			(layer "F.Fab")
		)
		(fp_line
			(start 0.67945 -0.3048)
			(end 0.67945 0.3048)
			(stroke
				(width 0.1)
				(type default)
			)
			(layer "F.Fab")
		)
		(fp_line
			(start 0.67945 0.3048)
			(end 0.120396 0.3048)
			(stroke
				(width 0.1)
				(type default)
			)
			(layer "F.Fab")
		)
		(pad "1" smd circle
			(at -0.40005 0)
			(size 0 0)
			(layers "F.Cu" "F.Mask" "F.Paste")
			(net "P3V3_AUX")
		)
		(pad "2" smd circle
			(at 0.40005 0)
			(size 0 0)
			(layers "F.Cu" "F.Mask" "F.Paste")
			(net "FM_REMOTE_DEBUG_DET_R")
		)
	)
	(footprint ""
		(layer "F.Cu")
		(at 23.767034 -384.978148 90)
		(property "Reference" "C2353"
			(at 0 0 90)
			(layer "F.SilkS")
			(hide yes)
			(effects
				(font
					(size 1.27 1.27)
				)
			)
		)
		(property "Value" ""
			(at 0 0 90)
			(layer "F.Fab")
			(effects
				(font
					(size 1.27 1.27)
				)
			)
		)
		(duplicate_pad_numbers_are_jumpers no)
		(fp_line
			(start 0.7874 -0.4064)
			(end 0.7874 0.4064)
			(stroke
				(width 0.1524)
				(type default)
			)
			(layer "F.SilkS")
		)
		(fp_line
			(start -0.7874 -0.4064)
			(end -0.036068 -0.4064)
			(stroke
				(width 0.1524)
				(type default)
			)
			(layer "F.SilkS")
		)
		(fp_line
			(start 0.7874 0.4064)
			(end -0.7874 0.4064)
			(stroke
				(width 0.1524)
				(type default)
			)
			(layer "F.SilkS")
		)
		(fp_line
			(start 0.6858 -0.3048)
			(end 0.6858 0.3048)
			(stroke
				(width 0.1)
				(type default)
			)
			(layer "F.Fab")
		)
		(fp_line
			(start 0.1016 -0.3048)
			(end 0.6858 -0.3048)
			(stroke
				(width 0.1)
				(type default)
			)
			(layer "F.Fab")
		)
		(fp_line
			(start -0.1016 -0.3048)
			(end -0.1016 -0.2794)
			(stroke
				(width 0.1)
				(type default)
			)
			(layer "F.Fab")
		)
		(fp_line
			(start -0.6858 -0.3048)
			(end -0.1016 -0.3048)
			(stroke
				(width 0.1)
				(type default)
			)
			(layer "F.Fab")
		)
		(fp_line
			(start 0.1016 -0.2794)
			(end 0.1016 -0.3048)
			(stroke
				(width 0.1)
				(type default)
			)
			(layer "F.Fab")
		)
		(fp_line
			(start -0.1016 -0.2794)
			(end 0.1016 -0.2794)
			(stroke
				(width 0.1)
				(type default)
			)
			(layer "F.Fab")
		)
		(fp_line
			(start 0.1016 0.2794)
			(end -0.1016 0.2794)
			(stroke
				(width 0.1)
				(type default)
			)
			(layer "F.Fab")
		)
		(fp_line
			(start -0.1016 0.2794)
			(end -0.1016 0.3048)
			(stroke
				(width 0.1)
				(type default)
			)
			(layer "F.Fab")
		)
		(fp_line
			(start 0.6858 0.3048)
			(end 0.1016 0.3048)
			(stroke
				(width 0.1)
				(type default)
			)
			(layer "F.Fab")
		)
		(fp_line
			(start 0.1016 0.3048)
			(end 0.1016 0.2794)
			(stroke
				(width 0.1)
				(type default)
			)
			(layer "F.Fab")
		)
		(fp_line
			(start -0.1016 0.3048)
			(end -0.6858 0.3048)
			(stroke
				(width 0.1)
				(type default)
			)
			(layer "F.Fab")
		)
		(fp_line
			(start -0.6858 0.3048)
			(end -0.6858 -0.3048)
			(stroke
				(width 0.1)
				(type default)
			)
			(layer "F.Fab")
		)
		(pad "1" smd rect
			(at -0.40005 0 270)
			(size 0.4572 0.508)
			(layers "F.Cu" "F.Mask" "F.Paste")
			(net "P2E_MB_BMC_RX_BUF2_C_DP<0>")
		)
		(pad "2" smd rect
			(at 0.40005 0 270)
			(size 0.4572 0.508)
			(layers "F.Cu" "F.Mask" "F.Paste")
			(net "P2E_MB_BMC_RX_BUF_DP<0>")
		)
	)
	(footprint ""
		(layer "F.Cu")
		(at 401.62988 -189.067948)
		(property "Reference" "R324"
			(at 0 0 0)
			(layer "F.SilkS")
			(hide yes)
			(effects
				(font
					(size 1.27 1.27)
				)
			)
		)
		(property "Value" ""
			(at 0 0 0)
			(layer "F.Fab")
			(effects
				(font
					(size 1.27 1.27)
				)
			)
		)
		(duplicate_pad_numbers_are_jumpers no)
		(fp_line
			(start -2.044192 -0.94361)
			(end -2.044192 0.898398)
			(stroke
				(width 0.1524)
				(type default)
			)
			(layer "F.SilkS")
		)
		(fp_line
			(start -2.044192 0.94361)
			(end 2.044192 0.94361)
			(stroke
				(width 0.1524)
				(type default)
			)
			(layer "F.SilkS")
		)
		(fp_line
			(start 2.044192 -0.94361)
			(end -2.044192 -0.94361)
			(stroke
				(width 0.1524)
				(type default)
			)
			(layer "F.SilkS")
		)
		(fp_line
			(start 2.044192 0.94361)
			(end 2.044192 -0.94361)
			(stroke
				(width 0.1524)
				(type default)
			)
			(layer "F.SilkS")
		)
		(fp_line
			(start -1.625092 -0.87503)
			(end -1.625092 0.87503)
			(stroke
				(width 0.1)
				(type default)
			)
			(layer "F.Fab")
		)
		(fp_line
			(start -1.625092 0.87503)
			(end 1.625092 0.87503)
			(stroke
				(width 0.1)
				(type default)
			)
			(layer "F.Fab")
		)
		(fp_line
			(start 1.625092 -0.87503)
			(end -1.625092 -0.87503)
			(stroke
				(width 0.1)
				(type default)
			)
			(layer "F.Fab")
		)
		(fp_line
			(start 1.625092 0.87503)
			(end 1.625092 -0.87503)
			(stroke
				(width 0.1)
				(type default)
			)
			(layer "F.Fab")
		)
		(pad "1" smd rect
			(at -1.450086 0)
			(size 0.9144 1.6002)
			(layers "F.Cu" "F.Mask" "F.Paste")
			(net "PVNN_MAIN_CPU0")
		)
		(pad "2" smd rect
			(at 1.450086 0)
			(size 0.9144 1.6002)
			(layers "F.Cu" "F.Mask" "F.Paste")
			(net "PVNN_TERM_CPU0")
		)
	)
	(footprint ""
		(layer "F.Cu")
		(at 166.078154 -402.371052 -90)
		(property "Reference" "C773"
			(at 0 0 270)
			(layer "F.SilkS")
			(hide yes)
			(effects
				(font
					(size 1.27 1.27)
				)
			)
		)
		(property "Value" ""
			(at 0 0 270)
			(layer "F.Fab")
			(effects
				(font
					(size 1.27 1.27)
				)
			)
		)
		(duplicate_pad_numbers_are_jumpers no)
		(fp_line
			(start -0.299974 0.150114)
			(end -0.299974 -0.150114)
			(stroke
				(width 0.1)
				(type default)
			)
			(layer "F.Fab")
		)
		(fp_line
			(start 0.299974 0.150114)
			(end -0.299974 0.150114)
			(stroke
				(width 0.1)
				(type default)
			)
			(layer "F.Fab")
		)
		(fp_line
			(start -0.299974 -0.150114)
			(end 0.299974 -0.150114)
			(stroke
				(width 0.1)
				(type default)
			)
			(layer "F.Fab")
		)
		(fp_line
			(start 0.299974 -0.150114)
			(end 0.299974 0.150114)
			(stroke
				(width 0.1)
				(type default)
			)
			(layer "F.Fab")
		)
		(pad "1" smd rect
			(at -0.2667 0 270)
			(size 0.3048 0.381)
			(layers "F.Cu" "F.Mask" "F.Paste")
			(net "P5E_CPU1_PE2_TX_C_DP<0>")
		)
		(pad "2" smd rect
			(at 0.2667 0 270)
			(size 0.3048 0.381)
			(layers "F.Cu" "F.Mask" "F.Paste")
			(net "P5E_CPU1_PE2_TX_DP<0>")
		)
	)
)
